(kicad_pcb
	(version 20260206)
	(generator "pcbnew")
	(generator_version "10.0")
	(general
		(thickness 1.6)
		(legacy_teardrops no)
	)
	(paper "A4")
	(title_block
		(title "v1-chassis-manager — T6M_CM_d_v01_1031_1645.brd")
		(comment 1 "Open CloudServer (Microsoft) / footprints 2443-2452 of 2512")
	)
	(layers
		(0 "F.Cu" signal "TOP")
		(4 "In1.Cu" signal "GND1")
		(6 "In2.Cu" signal "IN1")
		(8 "In3.Cu" signal "VCC1")
		(10 "In4.Cu" signal "VCC2")
		(12 "In5.Cu" signal "GND2")
		(14 "In6.Cu" signal "IN2")
		(16 "In7.Cu" signal "IN3")
		(18 "In8.Cu" signal "GND3")
		(2 "B.Cu" signal "BOTTOM")
		(9 "F.Adhes" user "F.Adhesive")
		(11 "B.Adhes" user "B.Adhesive")
		(13 "F.Paste" user "Package Geometry/Pastemask Top")
		(15 "B.Paste" user "Package Geometry/Pastemask Bottom")
		(5 "F.SilkS" user "Ref Des/Silkscreen Top")
		(7 "B.SilkS" user "Ref Des/Silkscreen Bottom")
		(1 "F.Mask" user "Board Geometry/Soldermask Top")
		(3 "B.Mask" user "Board Geometry/Soldermask Bottom")
		(17 "Dwgs.User" user "User.Drawings")
		(19 "Cmts.User" user "User.Comments")
		(21 "Eco1.User" user "User.Eco1")
		(23 "Eco2.User" user "User.Eco2")
		(25 "Edge.Cuts" user "Board Geometry/Outline")
		(27 "Margin" user)
		(31 "F.CrtYd" user "Package Geometry/Place Bound Top")
		(29 "B.CrtYd" user "Package Geometry/Place Bound Bottom")
		(35 "F.Fab" user "Ref Des/Assembly Top")
		(33 "B.Fab" user "Ref Des/Assembly Bottom")
	)
	(footprint ""
		(layer "B.Cu")
		(at 49.32299 -88.495886 90)
		(property "Reference" "R99"
			(at 0.90297 0.28575 270)
			(unlocked yes)
			(layer "B.SilkS")
			(effects
				(font
					(size 0.7874 0.5842)
					(thickness 0.1524)
				)
				(justify left mirror)
			)
		)
		(property "Value" ""
			(at 0 0 90)
			(layer "B.Fab")
			(effects
				(font
					(size 1.27 1.27)
				)
				(justify mirror)
			)
		)
		(duplicate_pad_numbers_are_jumpers no)
		(fp_line
			(start 0.7874 -0.4064)
			(end -0.7874 -0.4064)
			(stroke
				(width 0.1524)
				(type default)
			)
			(layer "B.SilkS")
		)
		(fp_line
			(start -0.7874 -0.4064)
			(end -0.7874 0.4064)
			(stroke
				(width 0.1524)
				(type default)
			)
			(layer "B.SilkS")
		)
		(fp_line
			(start 0.7874 0.4064)
			(end 0.7874 -0.4064)
			(stroke
				(width 0.1524)
				(type default)
			)
			(layer "B.SilkS")
		)
		(fp_line
			(start -0.7874 0.4064)
			(end 0.7874 0.4064)
			(stroke
				(width 0.1524)
				(type default)
			)
			(layer "B.SilkS")
		)
		(fp_poly
			(pts
				(xy 0.508 0.2794) (xy 0.508 0.2286) (xy 0.635 0.2286) (xy 0.635 -0.254) (xy 0.5334 -0.254) (xy 0.5334 -0.2794)
				(xy -0.5334 -0.2794) (xy -0.5334 -0.254) (xy -0.635 -0.254) (xy -0.635 0.254) (xy -0.5334 0.254)
				(xy -0.5334 0.2794)
			)
			(stroke
				(width 0)
				(type default)
			)
			(fill no)
			(layer "B.CrtYd")
		)
		(pad "1" smd rect
			(at -0.40005 0 270)
			(size 0.4572 0.508)
			(layers "B.Cu" "B.Mask" "B.Paste")
			(net "PD_NODE1_NTB_CLKINN")
		)
		(pad "2" smd rect
			(at 0.40005 0 270)
			(size 0.4572 0.508)
			(layers "B.Cu" "B.Mask" "B.Paste")
			(net "GND")
		)
	)
	(footprint ""
		(layer "B.Cu")
		(at 144.909032 -39.726616)
		(property "Reference" "R816"
			(at 1.24714 17.425924 0)
			(unlocked yes)
			(layer "B.SilkS")
			(effects
				(font
					(size 0.7874 0.5842)
					(thickness 0.1524)
				)
				(justify left mirror)
			)
		)
		(property "Value" ""
			(at 0 0 0)
			(layer "B.Fab")
			(effects
				(font
					(size 1.27 1.27)
				)
				(justify mirror)
			)
		)
		(duplicate_pad_numbers_are_jumpers no)
		(fp_line
			(start -0.7874 -0.4064)
			(end -0.7874 0.4064)
			(stroke
				(width 0.1524)
				(type default)
			)
			(layer "B.SilkS")
		)
		(fp_line
			(start -0.7874 0.4064)
			(end 0.7874 0.4064)
			(stroke
				(width 0.1524)
				(type default)
			)
			(layer "B.SilkS")
		)
		(fp_line
			(start 0.7874 -0.4064)
			(end -0.7874 -0.4064)
			(stroke
				(width 0.1524)
				(type default)
			)
			(layer "B.SilkS")
		)
		(fp_line
			(start 0.7874 0.4064)
			(end 0.7874 -0.4064)
			(stroke
				(width 0.1524)
				(type default)
			)
			(layer "B.SilkS")
		)
		(fp_poly
			(pts
				(xy 0.508 0.2794) (xy 0.508 0.2286) (xy 0.635 0.2286) (xy 0.635 -0.254) (xy 0.5334 -0.254) (xy 0.5334 -0.2794)
				(xy -0.5334 -0.2794) (xy -0.5334 -0.254) (xy -0.635 -0.254) (xy -0.635 0.254) (xy -0.5334 0.254)
				(xy -0.5334 0.2794)
			)
			(stroke
				(width 0)
				(type default)
			)
			(fill no)
			(layer "B.CrtYd")
		)
		(pad "1" smd rect
			(at -0.40005 0 180)
			(size 0.4572 0.508)
			(layers "B.Cu" "B.Mask" "B.Paste")
			(net "SIO_JTAG_CPLD2_TCK_R")
		)
		(pad "2" smd rect
			(at 0.40005 0 180)
			(size 0.4572 0.508)
			(layers "B.Cu" "B.Mask" "B.Paste")
			(net "P3V3_NODE1")
		)
	)
	(footprint ""
		(layer "B.Cu")
		(at 32.639 -187.7314 180)
		(property "Reference" "R1331"
			(at -1.3462 -1.01727 0)
			(unlocked yes)
			(layer "B.SilkS")
			(effects
				(font
					(size 0.7874 0.5842)
					(thickness 0.1524)
				)
				(justify left mirror)
			)
		)
		(property "Value" ""
			(at 0 0 0)
			(layer "B.Fab")
			(effects
				(font
					(size 1.27 1.27)
				)
				(justify mirror)
			)
		)
		(duplicate_pad_numbers_are_jumpers no)
		(fp_line
			(start 0.7874 0.4064)
			(end 0.7874 -0.4064)
			(stroke
				(width 0.1524)
				(type default)
			)
			(layer "B.SilkS")
		)
		(fp_line
			(start 0.7874 -0.4064)
			(end -0.7874 -0.4064)
			(stroke
				(width 0.1524)
				(type default)
			)
			(layer "B.SilkS")
		)
		(fp_line
			(start -0.7874 0.4064)
			(end 0.7874 0.4064)
			(stroke
				(width 0.1524)
				(type default)
			)
			(layer "B.SilkS")
		)
		(fp_line
			(start -0.7874 -0.4064)
			(end -0.7874 0.4064)
			(stroke
				(width 0.1524)
				(type default)
			)
			(layer "B.SilkS")
		)
		(fp_poly
			(pts
				(xy 0.508 0.2794) (xy 0.508 0.2286) (xy 0.635 0.2286) (xy 0.635 -0.254) (xy 0.5334 -0.254) (xy 0.5334 -0.2794)
				(xy -0.5334 -0.2794) (xy -0.5334 -0.254) (xy -0.635 -0.254) (xy -0.635 0.254) (xy -0.5334 0.254)
				(xy -0.5334 0.2794)
			)
			(stroke
				(width 0)
				(type default)
			)
			(fill no)
			(layer "B.CrtYd")
		)
		(pad "1" smd rect
			(at -0.40005 0)
			(size 0.4572 0.508)
			(layers "B.Cu" "B.Mask" "B.Paste")
			(net "UART_RI_P6_L_N_R")
		)
		(pad "2" smd rect
			(at 0.40005 0)
			(size 0.4572 0.508)
			(layers "B.Cu" "B.Mask" "B.Paste")
			(net "UART_RI_P6_L_N")
		)
	)
	(footprint ""
		(layer "B.Cu")
		(at 141.233652 -137.24255)
		(property "Reference" "C330"
			(at 4.0894 -2.773172 0)
			(unlocked yes)
			(layer "B.SilkS")
			(effects
				(font
					(size 0.7874 0.5842)
					(thickness 0.1524)
				)
				(justify left mirror)
			)
		)
		(property "Value" ""
			(at 0 0 0)
			(layer "B.Fab")
			(effects
				(font
					(size 1.27 1.27)
				)
				(justify mirror)
			)
		)
		(duplicate_pad_numbers_are_jumpers no)
		(fp_line
			(start -0.7874 -0.4064)
			(end -0.7874 0.4064)
			(stroke
				(width 0.1524)
				(type default)
			)
			(layer "B.SilkS")
		)
		(fp_line
			(start -0.7874 0.4064)
			(end 0.7874 0.4064)
			(stroke
				(width 0.1524)
				(type default)
			)
			(layer "B.SilkS")
		)
		(fp_line
			(start 0 0.381)
			(end 0 -0.381)
			(stroke
				(width 0.1524)
				(type default)
			)
			(layer "B.SilkS")
		)
		(fp_line
			(start 0.7874 -0.4064)
			(end -0.7874 -0.4064)
			(stroke
				(width 0.1524)
				(type default)
			)
			(layer "B.SilkS")
		)
		(fp_line
			(start 0.7874 0.4064)
			(end 0.7874 -0.4064)
			(stroke
				(width 0.1524)
				(type default)
			)
			(layer "B.SilkS")
		)
		(fp_poly
			(pts
				(xy 0.5334 0.254) (xy 0.635 0.254) (xy 0.635 0.2286) (xy 0.635 -0.254) (xy 0.5334 -0.254) (xy 0.5334 -0.2794)
				(xy -0.5334 -0.2794) (xy -0.5334 -0.254) (xy -0.635 -0.254) (xy -0.635 0.254) (xy -0.5334 0.254)
				(xy -0.5334 0.2794) (xy 0.508 0.2794) (xy 0.5334 0.2794)
			)
			(stroke
				(width 0)
				(type default)
			)
			(fill no)
			(layer "B.CrtYd")
		)
		(pad "1" smd rect
			(at -0.40005 0 180)
			(size 0.4572 0.508)
			(layers "B.Cu" "B.Mask" "B.Paste")
			(net "P1V0_NODE1")
		)
		(pad "2" smd rect
			(at 0.40005 0 180)
			(size 0.4572 0.508)
			(layers "B.Cu" "B.Mask" "B.Paste")
			(net "GND")
		)
	)
	(footprint ""
		(layer "B.Cu")
		(at 137.970006 -40.49141 180)
		(property "Reference" "R1065"
			(at 4.172458 -18.34261 0)
			(unlocked yes)
			(layer "B.SilkS")
			(effects
				(font
					(size 0.7874 0.5842)
					(thickness 0.1524)
				)
				(justify left mirror)
			)
		)
		(property "Value" ""
			(at 0 0 0)
			(layer "B.Fab")
			(effects
				(font
					(size 1.27 1.27)
				)
				(justify mirror)
			)
		)
		(duplicate_pad_numbers_are_jumpers no)
		(fp_line
			(start 0.7874 0.4064)
			(end 0.7874 -0.4064)
			(stroke
				(width 0.1524)
				(type default)
			)
			(layer "B.SilkS")
		)
		(fp_line
			(start 0.7874 -0.4064)
			(end -0.7874 -0.4064)
			(stroke
				(width 0.1524)
				(type default)
			)
			(layer "B.SilkS")
		)
		(fp_line
			(start -0.7874 0.4064)
			(end 0.7874 0.4064)
			(stroke
				(width 0.1524)
				(type default)
			)
			(layer "B.SilkS")
		)
		(fp_line
			(start -0.7874 -0.4064)
			(end -0.7874 0.4064)
			(stroke
				(width 0.1524)
				(type default)
			)
			(layer "B.SilkS")
		)
		(fp_poly
			(pts
				(xy 0.508 0.2794) (xy 0.508 0.2286) (xy 0.635 0.2286) (xy 0.635 -0.254) (xy 0.5334 -0.254) (xy 0.5334 -0.2794)
				(xy -0.5334 -0.2794) (xy -0.5334 -0.254) (xy -0.635 -0.254) (xy -0.635 0.254) (xy -0.5334 0.254)
				(xy -0.5334 0.2794)
			)
			(stroke
				(width 0)
				(type default)
			)
			(fill no)
			(layer "B.CrtYd")
		)
		(pad "1" smd rect
			(at -0.40005 0)
			(size 0.4572 0.508)
			(layers "B.Cu" "B.Mask" "B.Paste")
			(net "SIO_JTAG_CPLD2_TMS_R")
		)
		(pad "2" smd rect
			(at 0.40005 0)
			(size 0.4572 0.508)
			(layers "B.Cu" "B.Mask" "B.Paste")
			(net "P3V3_NODE1")
		)
	)
	(footprint ""
		(layer "B.Cu")
		(at 37.912802 -150.910798 180)
		(property "Reference" "C426"
			(at 6.961378 10.661396 0)
			(unlocked yes)
			(layer "B.SilkS")
			(effects
				(font
					(size 0.7874 0.5842)
					(thickness 0.1524)
				)
				(justify left mirror)
			)
		)
		(property "Value" ""
			(at 0 0 0)
			(layer "B.Fab")
			(effects
				(font
					(size 1.27 1.27)
				)
				(justify mirror)
			)
		)
		(duplicate_pad_numbers_are_jumpers no)
		(fp_line
			(start 0.7874 0.4064)
			(end 0.7874 -0.4064)
			(stroke
				(width 0.1524)
				(type default)
			)
			(layer "B.SilkS")
		)
		(fp_line
			(start 0.7874 -0.4064)
			(end -0.7874 -0.4064)
			(stroke
				(width 0.1524)
				(type default)
			)
			(layer "B.SilkS")
		)
		(fp_line
			(start 0 0.381)
			(end 0 -0.381)
			(stroke
				(width 0.1524)
				(type default)
			)
			(layer "B.SilkS")
		)
		(fp_line
			(start -0.7874 0.4064)
			(end 0.7874 0.4064)
			(stroke
				(width 0.1524)
				(type default)
			)
			(layer "B.SilkS")
		)
		(fp_line
			(start -0.7874 -0.4064)
			(end -0.7874 0.4064)
			(stroke
				(width 0.1524)
				(type default)
			)
			(layer "B.SilkS")
		)
		(fp_poly
			(pts
				(xy 0.5334 0.254) (xy 0.635 0.254) (xy 0.635 0.2286) (xy 0.635 -0.254) (xy 0.5334 -0.254) (xy 0.5334 -0.2794)
				(xy -0.5334 -0.2794) (xy -0.5334 -0.254) (xy -0.635 -0.254) (xy -0.635 0.254) (xy -0.5334 0.254)
				(xy -0.5334 0.2794) (xy 0.508 0.2794) (xy 0.5334 0.2794)
			)
			(stroke
				(width 0)
				(type default)
			)
			(fill no)
			(layer "B.CrtYd")
		)
		(pad "1" smd rect
			(at -0.40005 0)
			(size 0.4572 0.508)
			(layers "B.Cu" "B.Mask" "B.Paste")
			(net "P1V9_LAN1")
		)
		(pad "2" smd rect
			(at 0.40005 0)
			(size 0.4572 0.508)
			(layers "B.Cu" "B.Mask" "B.Paste")
			(net "GND")
		)
	)
	(footprint ""
		(layer "B.Cu")
		(at 135.196834 -39.407084 180)
		(property "Reference" "R1191"
			(at 5.415788 -18.226532 0)
			(unlocked yes)
			(layer "B.SilkS")
			(effects
				(font
					(size 0.7874 0.5842)
					(thickness 0.1524)
				)
				(justify left mirror)
			)
		)
		(property "Value" ""
			(at 0 0 0)
			(layer "B.Fab")
			(effects
				(font
					(size 1.27 1.27)
				)
				(justify mirror)
			)
		)
		(duplicate_pad_numbers_are_jumpers no)
		(fp_line
			(start 0.7874 0.4064)
			(end 0.7874 -0.4064)
			(stroke
				(width 0.1524)
				(type default)
			)
			(layer "B.SilkS")
		)
		(fp_line
			(start 0.7874 -0.4064)
			(end -0.7874 -0.4064)
			(stroke
				(width 0.1524)
				(type default)
			)
			(layer "B.SilkS")
		)
		(fp_line
			(start -0.7874 0.4064)
			(end 0.7874 0.4064)
			(stroke
				(width 0.1524)
				(type default)
			)
			(layer "B.SilkS")
		)
		(fp_line
			(start -0.7874 -0.4064)
			(end -0.7874 0.4064)
			(stroke
				(width 0.1524)
				(type default)
			)
			(layer "B.SilkS")
		)
		(fp_poly
			(pts
				(xy 0.508 0.2794) (xy 0.508 0.2286) (xy 0.635 0.2286) (xy 0.635 -0.254) (xy 0.5334 -0.254) (xy 0.5334 -0.2794)
				(xy -0.5334 -0.2794) (xy -0.5334 -0.254) (xy -0.635 -0.254) (xy -0.635 0.254) (xy -0.5334 0.254)
				(xy -0.5334 0.2794)
			)
			(stroke
				(width 0)
				(type default)
			)
			(fill no)
			(layer "B.CrtYd")
		)
		(pad "1" smd rect
			(at -0.40005 0)
			(size 0.4572 0.508)
			(layers "B.Cu" "B.Mask" "B.Paste")
			(net "SIO_JTAG_CPLD2_TMS")
		)
		(pad "2" smd rect
			(at 0.40005 0)
			(size 0.4572 0.508)
			(layers "B.Cu" "B.Mask" "B.Paste")
			(net "GND")
		)
	)
	(footprint ""
		(layer "B.Cu")
		(at 67.670172 -148.280628)
		(property "Reference" "PJ18"
			(at -0.278892 -0.415036 270)
			(unlocked yes)
			(layer "B.SilkS")
			(effects
				(font
					(size 0.7874 0.5842)
					(thickness 0.1524)
				)
				(justify left mirror)
			)
		)
		(property "Value" ""
			(at 0 0 0)
			(layer "B.Fab")
			(effects
				(font
					(size 1.27 1.27)
				)
				(justify mirror)
			)
		)
		(duplicate_pad_numbers_are_jumpers no)
		(fp_poly
			(pts
				(xy -0.2794 0.907796) (xy -0.254 0.907796) (xy -0.254 1.0414) (xy 0.254 1.0414) (xy 0.254 1.034796)
				(xy 0.254 0.933196) (xy 0.2794 0.933196) (xy 0.2794 -0.133604) (xy 0.254 -0.133604) (xy 0.254 -0.235204)
				(xy -0.254 -0.235204) (xy -0.254 -0.133604) (xy -0.2794 -0.133604)
			)
			(stroke
				(width 0)
				(type default)
			)
			(fill no)
			(layer "B.CrtYd")
		)
		(pad "1" smd custom
			(at 0 -0.000254 180)
			(size 0.127 0.127)
			(layers "B.Cu" "B.Mask" "B.Paste")
			(net "Net_466")
			(options
				(clearance outline)
				(anchor circle)
			)
			(primitives
				(gr_poly
					(pts
						(xy -0.127 -0.508) (xy -0.127 0.0508) (xy -0.254 0.0508) (xy -0.254 0.508) (xy 0.254 0.508) (xy 0.254 0.0508)
						(xy 0.127 0.0508) (xy 0.127 -0.508)
					)
					(width 0)
					(fill yes)
				)
			)
		)
		(pad "2" smd rect
			(at 0 0.799846 90)
			(size 0.4572 0.508)
			(layers "B.Cu" "B.Mask" "B.Paste")
			(net "BMC_DEBUG_RXD")
		)
		(zone
			(layer "B.Cu")
			(hatch none 0.5)
			(connect_pads
				(clearance 0)
			)
			(min_thickness 0.25)
			(keepout
				(tracks allowed)
				(vias not_allowed)
				(pads allowed)
				(copperpour not_allowed)
				(footprints allowed)
			)
			(placement
				(enabled no)
				(sheetname "")
			)
			(fill
				(thermal_gap 0.5)
				(thermal_bridge_width 0.5)
				(island_removal_mode 0)
			)
			(polygon
				(pts
					(xy 67.974972 -147.195032) (xy 67.365372 -147.195032) (xy 67.365372 -148.566632) (xy 67.974972 -148.566632)
				)
			)
		)
	)
	(footprint ""
		(layer "B.Cu")
		(at 158.48076 -184.951624 -90)
		(property "Reference" "C669"
			(at -4.230624 1.999488 270)
			(unlocked yes)
			(layer "B.SilkS")
			(effects
				(font
					(size 0.7874 0.5842)
					(thickness 0.1524)
				)
				(justify left mirror)
			)
		)
		(property "Value" ""
			(at 0 0 90)
			(layer "B.Fab")
			(effects
				(font
					(size 1.27 1.27)
				)
				(justify mirror)
			)
		)
		(duplicate_pad_numbers_are_jumpers no)
		(fp_line
			(start -0.7874 0.4064)
			(end 0.7874 0.4064)
			(stroke
				(width 0.1524)
				(type default)
			)
			(layer "B.SilkS")
		)
		(fp_line
			(start 0.7874 0.4064)
			(end 0.7874 -0.4064)
			(stroke
				(width 0.1524)
				(type default)
			)
			(layer "B.SilkS")
		)
		(fp_line
			(start 0 0.381)
			(end 0 -0.381)
			(stroke
				(width 0.1524)
				(type default)
			)
			(layer "B.SilkS")
		)
		(fp_line
			(start -0.7874 -0.4064)
			(end -0.7874 0.4064)
			(stroke
				(width 0.1524)
				(type default)
			)
			(layer "B.SilkS")
		)
		(fp_line
			(start 0.7874 -0.4064)
			(end -0.7874 -0.4064)
			(stroke
				(width 0.1524)
				(type default)
			)
			(layer "B.SilkS")
		)
		(fp_poly
			(pts
				(xy 0.5334 0.254) (xy 0.635 0.254) (xy 0.635 0.2286) (xy 0.635 -0.254) (xy 0.5334 -0.254) (xy 0.5334 -0.2794)
				(xy -0.5334 -0.2794) (xy -0.5334 -0.254) (xy -0.635 -0.254) (xy -0.635 0.254) (xy -0.5334 0.254)
				(xy -0.5334 0.2794) (xy 0.508 0.2794) (xy 0.5334 0.2794)
			)
			(stroke
				(width 0)
				(type default)
			)
			(fill no)
			(layer "B.CrtYd")
		)
		(pad "1" smd rect
			(at -0.40005 0 90)
			(size 0.4572 0.508)
			(layers "B.Cu" "B.Mask" "B.Paste")
			(net "T12_NODE4_EN_R")
		)
		(pad "2" smd rect
			(at 0.40005 0 90)
			(size 0.4572 0.508)
			(layers "B.Cu" "B.Mask" "B.Paste")
			(net "GND")
		)
	)
	(footprint ""
		(layer "B.Cu")
		(at 161.65576 -187.872624 90)
		(property "Reference" "R827"
			(at 4.565396 -4.179062 270)
			(unlocked yes)
			(layer "B.SilkS")
			(effects
				(font
					(size 0.7874 0.5842)
					(thickness 0.1524)
				)
				(justify left mirror)
			)
		)
		(property "Value" ""
			(at 0 0 90)
			(layer "B.Fab")
			(effects
				(font
					(size 1.27 1.27)
				)
				(justify mirror)
			)
		)
		(duplicate_pad_numbers_are_jumpers no)
		(fp_line
			(start 0.7874 -0.4064)
			(end -0.7874 -0.4064)
			(stroke
				(width 0.1524)
				(type default)
			)
			(layer "B.SilkS")
		)
		(fp_line
			(start -0.7874 -0.4064)
			(end -0.7874 0.4064)
			(stroke
				(width 0.1524)
				(type default)
			)
			(layer "B.SilkS")
		)
		(fp_line
			(start 0.7874 0.4064)
			(end 0.7874 -0.4064)
			(stroke
				(width 0.1524)
				(type default)
			)
			(layer "B.SilkS")
		)
		(fp_line
			(start -0.7874 0.4064)
			(end 0.7874 0.4064)
			(stroke
				(width 0.1524)
				(type default)
			)
			(layer "B.SilkS")
		)
		(fp_poly
			(pts
				(xy 0.508 0.2794) (xy 0.508 0.2286) (xy 0.635 0.2286) (xy 0.635 -0.254) (xy 0.5334 -0.254) (xy 0.5334 -0.2794)
				(xy -0.5334 -0.2794) (xy -0.5334 -0.254) (xy -0.635 -0.254) (xy -0.635 0.254) (xy -0.5334 0.254)
				(xy -0.5334 0.2794)
			)
			(stroke
				(width 0)
				(type default)
			)
			(fill no)
			(layer "B.CrtYd")
		)
		(pad "1" smd rect
			(at -0.40005 0 270)
			(size 0.4572 0.508)
			(layers "B.Cu" "B.Mask" "B.Paste")
			(net "FAN4_TACH")
		)
		(pad "2" smd rect
			(at 0.40005 0 270)
			(size 0.4572 0.508)
			(layers "B.Cu" "B.Mask" "B.Paste")
			(net "FAN4_TACH_R")
		)
	)
)
